(kicad_pcb
	(version 20260206)
	(generator "pcbnew")
	(generator_version "10.0")
	(general
		(thickness 1.6)
		(legacy_teardrops no)
	)
	(paper "A4")
	(title_block
		(title "v1-chassis-manager — T6M_CM_d_v01_1031_1645.brd")
		(comment 1 "Open CloudServer (Microsoft) / footprints 150-159 of 2512")
	)
	(layers
		(0 "F.Cu" signal "TOP")
		(4 "In1.Cu" signal "GND1")
		(6 "In2.Cu" signal "IN1")
		(8 "In3.Cu" signal "VCC1")
		(10 "In4.Cu" signal "VCC2")
		(12 "In5.Cu" signal "GND2")
		(14 "In6.Cu" signal "IN2")
		(16 "In7.Cu" signal "IN3")
		(18 "In8.Cu" signal "GND3")
		(2 "B.Cu" signal "BOTTOM")
		(9 "F.Adhes" user "F.Adhesive")
		(11 "B.Adhes" user "B.Adhesive")
		(13 "F.Paste" user "Package Geometry/Pastemask Top")
		(15 "B.Paste" user "Package Geometry/Pastemask Bottom")
		(5 "F.SilkS" user "Ref Des/Silkscreen Top")
		(7 "B.SilkS" user "Ref Des/Silkscreen Bottom")
		(1 "F.Mask" user "Board Geometry/Soldermask Top")
		(3 "B.Mask" user "Board Geometry/Soldermask Bottom")
		(17 "Dwgs.User" user "User.Drawings")
		(19 "Cmts.User" user "User.Comments")
		(21 "Eco1.User" user "User.Eco1")
		(23 "Eco2.User" user "User.Eco2")
		(25 "Edge.Cuts" user "Board Geometry/Outline")
		(27 "Margin" user)
		(31 "F.CrtYd" user "Package Geometry/Place Bound Top")
		(29 "B.CrtYd" user "Package Geometry/Place Bound Bottom")
		(35 "F.Fab" user "Ref Des/Assembly Top")
		(33 "B.Fab" user "Ref Des/Assembly Bottom")
	)
	(footprint ""
		(layer "F.Cu")
		(at 69.755004 -165.662356 180)
		(property "Reference" "R676"
			(at 4.49072 0.046228 0)
			(unlocked yes)
			(layer "F.SilkS")
			(effects
				(font
					(size 0.7874 0.5842)
					(thickness 0.1524)
				)
				(justify left)
			)
		)
		(property "Value" ""
			(at 0 0 180)
			(layer "F.Fab")
			(effects
				(font
					(size 1.27 1.27)
				)
			)
		)
		(duplicate_pad_numbers_are_jumpers no)
		(fp_line
			(start 0.7874 0.4064)
			(end -0.7874 0.4064)
			(stroke
				(width 0.1524)
				(type default)
			)
			(layer "F.SilkS")
		)
		(fp_line
			(start 0.7874 -0.4064)
			(end 0.7874 0.4064)
			(stroke
				(width 0.1524)
				(type default)
			)
			(layer "F.SilkS")
		)
		(fp_line
			(start -0.7874 0.4064)
			(end -0.7874 -0.4064)
			(stroke
				(width 0.1524)
				(type default)
			)
			(layer "F.SilkS")
		)
		(fp_line
			(start -0.7874 -0.4064)
			(end 0.7874 -0.4064)
			(stroke
				(width 0.1524)
				(type default)
			)
			(layer "F.SilkS")
		)
		(fp_poly
			(pts
				(xy -0.508 0.2794) (xy -0.508 0.2286) (xy -0.635 0.2286) (xy -0.635 -0.254) (xy -0.5334 -0.254)
				(xy -0.5334 -0.2794) (xy 0.5334 -0.2794) (xy 0.5334 -0.254) (xy 0.635 -0.254) (xy 0.635 0.254) (xy 0.5334 0.254)
				(xy 0.5334 0.2794)
			)
			(stroke
				(width 0)
				(type default)
			)
			(fill no)
			(layer "F.CrtYd")
		)
		(pad "1" smd rect
			(at 0.40005 0 180)
			(size 0.4572 0.508)
			(layers "F.Cu" "F.Mask" "F.Paste")
			(net "CPLD123_RSV2")
		)
		(pad "2" smd rect
			(at -0.40005 0 180)
			(size 0.4572 0.508)
			(layers "F.Cu" "F.Mask" "F.Paste")
			(net "CPLD2_RSV2")
		)
	)
	(footprint ""
		(layer "F.Cu")
		(at 94.211394 -187.822586 180)
		(property "Reference" "C705"
			(at 1.182878 7.364984 0)
			(unlocked yes)
			(layer "F.SilkS")
			(effects
				(font
					(size 0.7874 0.5842)
					(thickness 0.1524)
				)
				(justify left)
			)
		)
		(property "Value" ""
			(at 0 0 180)
			(layer "F.Fab")
			(effects
				(font
					(size 1.27 1.27)
				)
			)
		)
		(duplicate_pad_numbers_are_jumpers no)
		(fp_line
			(start 0.7874 0.4064)
			(end -0.7874 0.4064)
			(stroke
				(width 0.1524)
				(type default)
			)
			(layer "F.SilkS")
		)
		(fp_line
			(start 0.7874 -0.4064)
			(end 0.7874 0.4064)
			(stroke
				(width 0.1524)
				(type default)
			)
			(layer "F.SilkS")
		)
		(fp_line
			(start 0 0.381)
			(end 0 -0.381)
			(stroke
				(width 0.1524)
				(type default)
			)
			(layer "F.SilkS")
		)
		(fp_line
			(start -0.7874 0.4064)
			(end -0.7874 -0.4064)
			(stroke
				(width 0.1524)
				(type default)
			)
			(layer "F.SilkS")
		)
		(fp_line
			(start -0.7874 -0.4064)
			(end 0.7874 -0.4064)
			(stroke
				(width 0.1524)
				(type default)
			)
			(layer "F.SilkS")
		)
		(fp_poly
			(pts
				(xy -0.5334 0.254) (xy -0.635 0.254) (xy -0.635 0.2286) (xy -0.635 -0.254) (xy -0.5334 -0.254) (xy -0.5334 -0.2794)
				(xy 0.5334 -0.2794) (xy 0.5334 -0.254) (xy 0.635 -0.254) (xy 0.635 0.254) (xy 0.5334 0.254) (xy 0.5334 0.2794)
				(xy -0.508 0.2794) (xy -0.5334 0.2794)
			)
			(stroke
				(width 0)
				(type default)
			)
			(fill no)
			(layer "F.CrtYd")
		)
		(pad "1" smd rect
			(at 0.40005 0 180)
			(size 0.4572 0.508)
			(layers "F.Cu" "F.Mask" "F.Paste")
			(net "UART_T6_NODE2_TXD_R")
		)
		(pad "2" smd rect
			(at -0.40005 0 180)
			(size 0.4572 0.508)
			(layers "F.Cu" "F.Mask" "F.Paste")
			(net "GND")
		)
	)
	(footprint ""
		(layer "F.Cu")
		(at 123.75896 -188.126624 90)
		(property "Reference" "C629"
			(at 4.949444 -0.396748 90)
			(unlocked yes)
			(layer "F.SilkS")
			(effects
				(font
					(size 0.7874 0.5842)
					(thickness 0.1524)
				)
				(justify left)
			)
		)
		(property "Value" ""
			(at 0 0 90)
			(layer "F.Fab")
			(effects
				(font
					(size 1.27 1.27)
				)
			)
		)
		(duplicate_pad_numbers_are_jumpers no)
		(fp_line
			(start 0.7874 -0.4064)
			(end 0.7874 0.4064)
			(stroke
				(width 0.1524)
				(type default)
			)
			(layer "F.SilkS")
		)
		(fp_line
			(start -0.7874 -0.4064)
			(end 0.7874 -0.4064)
			(stroke
				(width 0.1524)
				(type default)
			)
			(layer "F.SilkS")
		)
		(fp_line
			(start 0 0.381)
			(end 0 -0.381)
			(stroke
				(width 0.1524)
				(type default)
			)
			(layer "F.SilkS")
		)
		(fp_line
			(start 0.7874 0.4064)
			(end -0.7874 0.4064)
			(stroke
				(width 0.1524)
				(type default)
			)
			(layer "F.SilkS")
		)
		(fp_line
			(start -0.7874 0.4064)
			(end -0.7874 -0.4064)
			(stroke
				(width 0.1524)
				(type default)
			)
			(layer "F.SilkS")
		)
		(fp_poly
			(pts
				(xy -0.5334 0.254) (xy -0.635 0.254) (xy -0.635 0.2286) (xy -0.635 -0.254) (xy -0.5334 -0.254) (xy -0.5334 -0.2794)
				(xy 0.5334 -0.2794) (xy 0.5334 -0.254) (xy 0.635 -0.254) (xy 0.635 0.254) (xy 0.5334 0.254) (xy 0.5334 0.2794)
				(xy -0.508 0.2794) (xy -0.5334 0.2794)
			)
			(stroke
				(width 0)
				(type default)
			)
			(fill no)
			(layer "F.CrtYd")
		)
		(pad "1" smd rect
			(at 0.40005 0 90)
			(size 0.4572 0.508)
			(layers "F.Cu" "F.Mask" "F.Paste")
			(net "T8_NODE3_EN_R")
		)
		(pad "2" smd rect
			(at -0.40005 0 90)
			(size 0.4572 0.508)
			(layers "F.Cu" "F.Mask" "F.Paste")
			(net "GND")
		)
	)
	(footprint ""
		(layer "F.Cu")
		(at 65.38976 -185.205624 -90)
		(property "Reference" "R880"
			(at -4.006088 0.811022 90)
			(unlocked yes)
			(layer "F.SilkS")
			(effects
				(font
					(size 0.7874 0.5842)
					(thickness 0.1524)
				)
				(justify left)
			)
		)
		(property "Value" ""
			(at 0 0 270)
			(layer "F.Fab")
			(effects
				(font
					(size 1.27 1.27)
				)
			)
		)
		(duplicate_pad_numbers_are_jumpers no)
		(fp_line
			(start -0.7874 0.4064)
			(end -0.7874 -0.4064)
			(stroke
				(width 0.1524)
				(type default)
			)
			(layer "F.SilkS")
		)
		(fp_line
			(start 0.7874 0.4064)
			(end -0.7874 0.4064)
			(stroke
				(width 0.1524)
				(type default)
			)
			(layer "F.SilkS")
		)
		(fp_line
			(start -0.7874 -0.4064)
			(end 0.7874 -0.4064)
			(stroke
				(width 0.1524)
				(type default)
			)
			(layer "F.SilkS")
		)
		(fp_line
			(start 0.7874 -0.4064)
			(end 0.7874 0.4064)
			(stroke
				(width 0.1524)
				(type default)
			)
			(layer "F.SilkS")
		)
		(fp_poly
			(pts
				(xy -0.508 0.2794) (xy -0.508 0.2286) (xy -0.635 0.2286) (xy -0.635 -0.254) (xy -0.5334 -0.254)
				(xy -0.5334 -0.2794) (xy 0.5334 -0.2794) (xy 0.5334 -0.254) (xy 0.635 -0.254) (xy 0.635 0.254) (xy 0.5334 0.254)
				(xy 0.5334 0.2794)
			)
			(stroke
				(width 0)
				(type default)
			)
			(fill no)
			(layer "F.CrtYd")
		)
		(pad "1" smd rect
			(at 0.40005 0 270)
			(size 0.4572 0.508)
			(layers "F.Cu" "F.Mask" "F.Paste")
			(net "T2_NODE4_EN")
		)
		(pad "2" smd rect
			(at -0.40005 0 270)
			(size 0.4572 0.508)
			(layers "F.Cu" "F.Mask" "F.Paste")
			(net "T2_NODE4_EN_R")
		)
	)
	(footprint ""
		(layer "F.Cu")
		(at 108.178346 -143.79575)
		(property "Reference" "PR72"
			(at -0.863854 -3.066542 0)
			(unlocked yes)
			(layer "F.SilkS")
			(effects
				(font
					(size 0.635 0.4064)
					(thickness 0.1524)
				)
				(justify left)
			)
		)
		(property "Value" ""
			(at 0 0 0)
			(layer "F.Fab")
			(effects
				(font
					(size 1.27 1.27)
				)
			)
		)
		(duplicate_pad_numbers_are_jumpers no)
		(fp_line
			(start -0.7874 -0.4064)
			(end 0.7874 -0.4064)
			(stroke
				(width 0.1524)
				(type default)
			)
			(layer "F.SilkS")
		)
		(fp_line
			(start -0.7874 0.4064)
			(end -0.7874 -0.4064)
			(stroke
				(width 0.1524)
				(type default)
			)
			(layer "F.SilkS")
		)
		(fp_line
			(start 0.7874 -0.4064)
			(end 0.7874 0.4064)
			(stroke
				(width 0.1524)
				(type default)
			)
			(layer "F.SilkS")
		)
		(fp_line
			(start 0.7874 0.4064)
			(end -0.7874 0.4064)
			(stroke
				(width 0.1524)
				(type default)
			)
			(layer "F.SilkS")
		)
		(fp_poly
			(pts
				(xy -0.508 0.2794) (xy -0.508 0.2286) (xy -0.635 0.2286) (xy -0.635 -0.254) (xy -0.5334 -0.254)
				(xy -0.5334 -0.2794) (xy 0.5334 -0.2794) (xy 0.5334 -0.254) (xy 0.635 -0.254) (xy 0.635 0.254) (xy 0.5334 0.254)
				(xy 0.5334 0.2794)
			)
			(stroke
				(width 0)
				(type default)
			)
			(fill no)
			(layer "F.CrtYd")
		)
		(pad "1" smd rect
			(at 0.40005 0)
			(size 0.4572 0.508)
			(layers "F.Cu" "F.Mask" "F.Paste")
			(net "VR_PVCCP_NODE1_VCC")
		)
		(pad "2" smd rect
			(at -0.40005 0)
			(size 0.4572 0.508)
			(layers "F.Cu" "F.Mask" "F.Paste")
			(net "VR_PVCCP_NODE1_TSEN_R")
		)
	)
	(footprint ""
		(layer "F.Cu")
		(at 180.765704 -11.53668 90)
		(property "Reference" "R817"
			(at -0.869696 -2.188972 90)
			(unlocked yes)
			(layer "F.SilkS")
			(effects
				(font
					(size 0.7874 0.5842)
					(thickness 0.1524)
				)
				(justify left)
			)
		)
		(property "Value" ""
			(at 0 0 90)
			(layer "F.Fab")
			(effects
				(font
					(size 1.27 1.27)
				)
			)
		)
		(duplicate_pad_numbers_are_jumpers no)
		(fp_line
			(start 0.7874 -0.4064)
			(end 0.7874 0.4064)
			(stroke
				(width 0.1524)
				(type default)
			)
			(layer "F.SilkS")
		)
		(fp_line
			(start -0.7874 -0.4064)
			(end 0.7874 -0.4064)
			(stroke
				(width 0.1524)
				(type default)
			)
			(layer "F.SilkS")
		)
		(fp_line
			(start 0.7874 0.4064)
			(end -0.7874 0.4064)
			(stroke
				(width 0.1524)
				(type default)
			)
			(layer "F.SilkS")
		)
		(fp_line
			(start -0.7874 0.4064)
			(end -0.7874 -0.4064)
			(stroke
				(width 0.1524)
				(type default)
			)
			(layer "F.SilkS")
		)
		(fp_poly
			(pts
				(xy -0.508 0.2794) (xy -0.508 0.2286) (xy -0.635 0.2286) (xy -0.635 -0.254) (xy -0.5334 -0.254)
				(xy -0.5334 -0.2794) (xy 0.5334 -0.2794) (xy 0.5334 -0.254) (xy 0.635 -0.254) (xy 0.635 0.254) (xy 0.5334 0.254)
				(xy 0.5334 0.2794)
			)
			(stroke
				(width 0)
				(type default)
			)
			(fill no)
			(layer "F.CrtYd")
		)
		(pad "1" smd rect
			(at 0.40005 0 90)
			(size 0.4572 0.508)
			(layers "F.Cu" "F.Mask" "F.Paste")
			(net "LED_PWR_NODE1_L")
		)
		(pad "2" smd rect
			(at -0.40005 0 90)
			(size 0.4572 0.508)
			(layers "F.Cu" "F.Mask" "F.Paste")
			(net "LED_PWR_GD")
		)
	)
	(footprint ""
		(layer "F.Cu")
		(at 176.666398 -36.848034)
		(property "Reference" "C558"
			(at -4.146042 0.612902 0)
			(unlocked yes)
			(layer "F.SilkS")
			(effects
				(font
					(size 0.7874 0.5842)
					(thickness 0.1524)
				)
				(justify left)
			)
		)
		(property "Value" ""
			(at 0 0 0)
			(layer "F.Fab")
			(effects
				(font
					(size 1.27 1.27)
				)
			)
		)
		(duplicate_pad_numbers_are_jumpers no)
		(fp_line
			(start -0.7874 -0.4064)
			(end 0.7874 -0.4064)
			(stroke
				(width 0.1524)
				(type default)
			)
			(layer "F.SilkS")
		)
		(fp_line
			(start -0.7874 0.4064)
			(end -0.7874 -0.4064)
			(stroke
				(width 0.1524)
				(type default)
			)
			(layer "F.SilkS")
		)
		(fp_line
			(start 0 0.381)
			(end 0 -0.381)
			(stroke
				(width 0.1524)
				(type default)
			)
			(layer "F.SilkS")
		)
		(fp_line
			(start 0.7874 -0.4064)
			(end 0.7874 0.4064)
			(stroke
				(width 0.1524)
				(type default)
			)
			(layer "F.SilkS")
		)
		(fp_line
			(start 0.7874 0.4064)
			(end -0.7874 0.4064)
			(stroke
				(width 0.1524)
				(type default)
			)
			(layer "F.SilkS")
		)
		(fp_poly
			(pts
				(xy -0.5334 0.254) (xy -0.635 0.254) (xy -0.635 0.2286) (xy -0.635 -0.254) (xy -0.5334 -0.254) (xy -0.5334 -0.2794)
				(xy 0.5334 -0.2794) (xy 0.5334 -0.254) (xy 0.635 -0.254) (xy 0.635 0.254) (xy 0.5334 0.254) (xy 0.5334 0.2794)
				(xy -0.508 0.2794) (xy -0.5334 0.2794)
			)
			(stroke
				(width 0)
				(type default)
			)
			(fill no)
			(layer "F.CrtYd")
		)
		(pad "1" smd rect
			(at 0.40005 0)
			(size 0.4572 0.508)
			(layers "F.Cu" "F.Mask" "F.Paste")
			(net "USBPWR_P0")
		)
		(pad "2" smd rect
			(at -0.40005 0)
			(size 0.4572 0.508)
			(layers "F.Cu" "F.Mask" "F.Paste")
			(net "GND")
		)
	)
	(footprint ""
		(layer "F.Cu")
		(at 88.232488 -153.673302)
		(property "Reference" "PC38"
			(at -1.467104 4.67614 0)
			(unlocked yes)
			(layer "F.SilkS")
			(effects
				(font
					(size 0.7874 0.5842)
					(thickness 0.1524)
				)
				(justify left)
			)
		)
		(property "Value" ""
			(at 0 0 0)
			(layer "F.Fab")
			(effects
				(font
					(size 1.27 1.27)
				)
			)
		)
		(duplicate_pad_numbers_are_jumpers no)
		(fp_line
			(start -1.905 -0.8636)
			(end 1.905 -0.8636)
			(stroke
				(width 0.1524)
				(type default)
			)
			(layer "F.SilkS")
		)
		(fp_line
			(start -1.905 0.8636)
			(end -1.905 -0.8636)
			(stroke
				(width 0.1524)
				(type default)
			)
			(layer "F.SilkS")
		)
		(fp_line
			(start 0 0.8382)
			(end 0 -0.8382)
			(stroke
				(width 0.1524)
				(type default)
			)
			(layer "F.SilkS")
		)
		(fp_line
			(start 1.905 -0.8636)
			(end 1.905 0.8636)
			(stroke
				(width 0.1524)
				(type default)
			)
			(layer "F.SilkS")
		)
		(fp_line
			(start 1.905 0.8636)
			(end -1.905 0.8636)
			(stroke
				(width 0.1524)
				(type default)
			)
			(layer "F.SilkS")
		)
		(fp_rect
			(start -1.524 0.7366)
			(end 1.524 -0.7366)
			(stroke
				(width 0)
				(type default)
			)
			(fill no)
			(layer "F.CrtYd")
		)
		(pad "1" smd rect
			(at 0.94996 0)
			(size 1.1176 1.3716)
			(layers "F.Cu" "F.Mask" "F.Paste")
			(net "P1V8_STB_NODE1")
		)
		(pad "2" smd rect
			(at -0.94996 0)
			(size 1.1176 1.3716)
			(layers "F.Cu" "F.Mask" "F.Paste")
			(net "GND")
		)
	)
	(footprint ""
		(layer "F.Cu")
		(at 167.622982 -131.768088 90)
		(property "Reference" "R627"
			(at -2.067052 -3.003296 90)
			(unlocked yes)
			(layer "F.SilkS")
			(effects
				(font
					(size 0.7874 0.5842)
					(thickness 0.1524)
				)
				(justify left)
			)
		)
		(property "Value" ""
			(at 0 0 90)
			(layer "F.Fab")
			(effects
				(font
					(size 1.27 1.27)
				)
			)
		)
		(duplicate_pad_numbers_are_jumpers no)
		(fp_line
			(start 0.7874 -0.4064)
			(end 0.7874 0.4064)
			(stroke
				(width 0.1524)
				(type default)
			)
			(layer "F.SilkS")
		)
		(fp_line
			(start -0.7874 -0.4064)
			(end 0.7874 -0.4064)
			(stroke
				(width 0.1524)
				(type default)
			)
			(layer "F.SilkS")
		)
		(fp_line
			(start 0.7874 0.4064)
			(end -0.7874 0.4064)
			(stroke
				(width 0.1524)
				(type default)
			)
			(layer "F.SilkS")
		)
		(fp_line
			(start -0.7874 0.4064)
			(end -0.7874 -0.4064)
			(stroke
				(width 0.1524)
				(type default)
			)
			(layer "F.SilkS")
		)
		(fp_poly
			(pts
				(xy -0.508 0.2794) (xy -0.508 0.2286) (xy -0.635 0.2286) (xy -0.635 -0.254) (xy -0.5334 -0.254)
				(xy -0.5334 -0.2794) (xy 0.5334 -0.2794) (xy 0.5334 -0.254) (xy 0.635 -0.254) (xy 0.635 0.254) (xy 0.5334 0.254)
				(xy 0.5334 0.2794)
			)
			(stroke
				(width 0)
				(type default)
			)
			(fill no)
			(layer "F.CrtYd")
		)
		(pad "1" smd rect
			(at 0.40005 0 90)
			(size 0.4572 0.508)
			(layers "F.Cu" "F.Mask" "F.Paste")
			(net "CPLD123_RSV1")
		)
		(pad "2" smd rect
			(at -0.40005 0 90)
			(size 0.4572 0.508)
			(layers "F.Cu" "F.Mask" "F.Paste")
			(net "CPLD1_RSV1")
		)
	)
	(footprint ""
		(layer "F.Cu")
		(at 67.749928 -106.303572 -90)
		(property "Reference" "R1238"
			(at 0.174244 -7.77621 90)
			(unlocked yes)
			(layer "F.SilkS")
			(effects
				(font
					(size 0.7874 0.5842)
					(thickness 0.1524)
				)
				(justify left)
			)
		)
		(property "Value" ""
			(at 0 0 270)
			(layer "F.Fab")
			(effects
				(font
					(size 1.27 1.27)
				)
			)
		)
		(duplicate_pad_numbers_are_jumpers no)
		(fp_line
			(start -0.7874 0.4064)
			(end -0.7874 -0.4064)
			(stroke
				(width 0.1524)
				(type default)
			)
			(layer "F.SilkS")
		)
		(fp_line
			(start 0.7874 0.4064)
			(end -0.7874 0.4064)
			(stroke
				(width 0.1524)
				(type default)
			)
			(layer "F.SilkS")
		)
		(fp_line
			(start -0.7874 -0.4064)
			(end 0.7874 -0.4064)
			(stroke
				(width 0.1524)
				(type default)
			)
			(layer "F.SilkS")
		)
		(fp_line
			(start 0.7874 -0.4064)
			(end 0.7874 0.4064)
			(stroke
				(width 0.1524)
				(type default)
			)
			(layer "F.SilkS")
		)
		(fp_poly
			(pts
				(xy -0.508 0.2794) (xy -0.508 0.2286) (xy -0.635 0.2286) (xy -0.635 -0.254) (xy -0.5334 -0.254)
				(xy -0.5334 -0.2794) (xy 0.5334 -0.2794) (xy 0.5334 -0.254) (xy 0.635 -0.254) (xy 0.635 0.254) (xy 0.5334 0.254)
				(xy 0.5334 0.2794)
			)
			(stroke
				(width 0)
				(type default)
			)
			(fill no)
			(layer "F.CrtYd")
		)
		(pad "1" smd rect
			(at 0.40005 0 270)
			(size 0.4572 0.508)
			(layers "F.Cu" "F.Mask" "F.Paste")
			(net "GND")
		)
		(pad "2" smd rect
			(at -0.40005 0 270)
			(size 0.4572 0.508)
			(layers "F.Cu" "F.Mask" "F.Paste")
			(net "FM_CPLD_NODE1_P1V8_EN")
		)
	)
)
